(kicad_pcb
	(version 20260206)
	(generator "pcbnew")
	(generator_version "10.0")
	(general
		(thickness 1.6)
		(legacy_teardrops no)
	)
	(paper "A4")
	(title_block
		(title "01162023_DA0F0TEBIF0_F0T_Expander_BD_F_brd_V02_OCP.brd")
		(comment 1 "Grand Teton / footprints 4023-4027 of 9728")
	)
	(layers
		(0 "F.Cu" signal "TOP")
		(4 "In1.Cu" signal "GND")
		(6 "In2.Cu" signal "VCC")
		(8 "In3.Cu" signal "VCC1")
		(10 "In4.Cu" signal "GND1")
		(12 "In5.Cu" signal "IN1")
		(14 "In6.Cu" signal "GND2")
		(16 "In7.Cu" signal "IN2")
		(18 "In8.Cu" signal "GND3")
		(20 "In9.Cu" signal "IN3")
		(22 "In10.Cu" signal "GND4")
		(24 "In11.Cu" signal "IN4")
		(26 "In12.Cu" signal "GND5")
		(28 "In13.Cu" signal "IN5")
		(30 "In14.Cu" signal "GND6")
		(32 "In15.Cu" signal "IN6")
		(34 "In16.Cu" signal "GND7")
		(2 "B.Cu" signal "BOTTOM")
		(9 "F.Adhes" user "F.Adhesive")
		(11 "B.Adhes" user "B.Adhesive")
		(13 "F.Paste" user "Package Geometry/Pastemask Top")
		(15 "B.Paste" user "Package Geometry/Pastemask Bottom")
		(5 "F.SilkS" user "Ref Des/Silkscreen Top")
		(7 "B.SilkS" user "Ref Des/Silkscreen Bottom")
		(1 "F.Mask" user "Board Geometry/Soldermask Top")
		(3 "B.Mask" user "Board Geometry/Soldermask Bottom")
		(17 "Dwgs.User" user "User.Drawings")
		(19 "Cmts.User" user "User.Comments")
		(21 "Eco1.User" user "User.Eco1")
		(23 "Eco2.User" user "User.Eco2")
		(25 "Edge.Cuts" user "Board Geometry/Outline")
		(27 "Margin" user)
		(31 "F.CrtYd" user "Package Geometry/Place Bound Top")
		(29 "B.CrtYd" user "Package Geometry/Place Bound Bottom")
		(35 "F.Fab" user "Ref Des/Assembly Top")
		(33 "B.Fab" user "Ref Des/Assembly Bottom")
	)
	(footprint ""
		(layer "F.Cu")
		(at 353.956366 -61.487812 180)
		(property "Reference" "R6012"
			(at 0 0 180)
			(layer "F.SilkS")
			(hide yes)
			(effects
				(font
					(size 1.27 1.27)
				)
			)
		)
		(property "Value" ""
			(at 0 0 180)
			(layer "F.Fab")
			(effects
				(font
					(size 1.27 1.27)
				)
			)
		)
		(duplicate_pad_numbers_are_jumpers no)
		(fp_line
			(start 0.7874 0.4064)
			(end -0.7874 0.4064)
			(stroke
				(width 0.1524)
				(type default)
			)
			(layer "F.SilkS")
		)
		(fp_line
			(start 0.7874 -0.4064)
			(end 0.7874 0.4064)
			(stroke
				(width 0.1524)
				(type default)
			)
			(layer "F.SilkS")
		)
		(fp_line
			(start -0.7874 0.4064)
			(end -0.7874 -0.4064)
			(stroke
				(width 0.1524)
				(type default)
			)
			(layer "F.SilkS")
		)
		(fp_line
			(start -0.7874 -0.4064)
			(end 0.7874 -0.4064)
			(stroke
				(width 0.1524)
				(type default)
			)
			(layer "F.SilkS")
		)
		(fp_line
			(start 0.67945 0.3048)
			(end 0.120396 0.3048)
			(stroke
				(width 0.1)
				(type default)
			)
			(layer "F.Fab")
		)
		(fp_line
			(start 0.67945 -0.3048)
			(end 0.67945 0.3048)
			(stroke
				(width 0.1)
				(type default)
			)
			(layer "F.Fab")
		)
		(fp_line
			(start 0.12065 -0.2794)
			(end 0.12065 -0.3048)
			(stroke
				(width 0.1)
				(type default)
			)
			(layer "F.Fab")
		)
		(fp_line
			(start 0.12065 -0.3048)
			(end 0.67945 -0.3048)
			(stroke
				(width 0.1)
				(type default)
			)
			(layer "F.Fab")
		)
		(fp_line
			(start 0.120396 0.3048)
			(end 0.120396 0.2794)
			(stroke
				(width 0.1)
				(type default)
			)
			(layer "F.Fab")
		)
		(fp_line
			(start 0.120396 0.2794)
			(end -0.12065 0.2794)
			(stroke
				(width 0.1)
				(type default)
			)
			(layer "F.Fab")
		)
		(fp_line
			(start -0.12065 0.3048)
			(end -0.67945 0.3048)
			(stroke
				(width 0.1)
				(type default)
			)
			(layer "F.Fab")
		)
		(fp_line
			(start -0.12065 0.2794)
			(end -0.12065 0.3048)
			(stroke
				(width 0.1)
				(type default)
			)
			(layer "F.Fab")
		)
		(fp_line
			(start -0.12065 -0.2794)
			(end 0.12065 -0.2794)
			(stroke
				(width 0.1)
				(type default)
			)
			(layer "F.Fab")
		)
		(fp_line
			(start -0.12065 -0.305054)
			(end -0.12065 -0.2794)
			(stroke
				(width 0.1)
				(type default)
			)
			(layer "F.Fab")
		)
		(fp_line
			(start -0.67945 0.3048)
			(end -0.67945 -0.305054)
			(stroke
				(width 0.1)
				(type default)
			)
			(layer "F.Fab")
		)
		(fp_line
			(start -0.67945 -0.305054)
			(end -0.12065 -0.305054)
			(stroke
				(width 0.1)
				(type default)
			)
			(layer "F.Fab")
		)
		(pad "1" smd circle
			(at -0.40005 0 180)
			(size 0 0)
			(layers "F.Cu" "F.Mask" "F.Paste")
			(net "P3V3_AUX")
		)
		(pad "2" smd circle
			(at 0.40005 0 180)
			(size 0 0)
			(layers "F.Cu" "F.Mask" "F.Paste")
			(net "PWRGD_P12V_SSD12_D")
		)
	)
	(footprint ""
		(layer "F.Cu")
		(at 202.90409 -289.230816 90)
		(property "Reference" "R3948"
			(at 0 0 90)
			(layer "F.SilkS")
			(hide yes)
			(effects
				(font
					(size 1.27 1.27)
				)
			)
		)
		(property "Value" ""
			(at 0 0 90)
			(layer "F.Fab")
			(effects
				(font
					(size 1.27 1.27)
				)
			)
		)
		(duplicate_pad_numbers_are_jumpers no)
		(fp_line
			(start 0.7874 -0.4064)
			(end 0.7874 0.4064)
			(stroke
				(width 0.1524)
				(type default)
			)
			(layer "F.SilkS")
		)
		(fp_line
			(start -0.7874 -0.4064)
			(end 0.7874 -0.4064)
			(stroke
				(width 0.1524)
				(type default)
			)
			(layer "F.SilkS")
		)
		(fp_line
			(start 0.7874 0.4064)
			(end -0.7874 0.4064)
			(stroke
				(width 0.1524)
				(type default)
			)
			(layer "F.SilkS")
		)
		(fp_line
			(start -0.7874 0.4064)
			(end -0.7874 -0.4064)
			(stroke
				(width 0.1524)
				(type default)
			)
			(layer "F.SilkS")
		)
		(fp_line
			(start -0.12065 -0.305054)
			(end -0.12065 -0.2794)
			(stroke
				(width 0.1)
				(type default)
			)
			(layer "F.Fab")
		)
		(fp_line
			(start -0.67945 -0.305054)
			(end -0.12065 -0.305054)
			(stroke
				(width 0.1)
				(type default)
			)
			(layer "F.Fab")
		)
		(fp_line
			(start 0.67945 -0.3048)
			(end 0.67945 0.3048)
			(stroke
				(width 0.1)
				(type default)
			)
			(layer "F.Fab")
		)
		(fp_line
			(start 0.12065 -0.3048)
			(end 0.67945 -0.3048)
			(stroke
				(width 0.1)
				(type default)
			)
			(layer "F.Fab")
		)
		(fp_line
			(start 0.12065 -0.2794)
			(end 0.12065 -0.3048)
			(stroke
				(width 0.1)
				(type default)
			)
			(layer "F.Fab")
		)
		(fp_line
			(start -0.12065 -0.2794)
			(end 0.12065 -0.2794)
			(stroke
				(width 0.1)
				(type default)
			)
			(layer "F.Fab")
		)
		(fp_line
			(start 0.120396 0.2794)
			(end -0.12065 0.2794)
			(stroke
				(width 0.1)
				(type default)
			)
			(layer "F.Fab")
		)
		(fp_line
			(start -0.12065 0.2794)
			(end -0.12065 0.3048)
			(stroke
				(width 0.1)
				(type default)
			)
			(layer "F.Fab")
		)
		(fp_line
			(start 0.67945 0.3048)
			(end 0.120396 0.3048)
			(stroke
				(width 0.1)
				(type default)
			)
			(layer "F.Fab")
		)
		(fp_line
			(start 0.120396 0.3048)
			(end 0.120396 0.2794)
			(stroke
				(width 0.1)
				(type default)
			)
			(layer "F.Fab")
		)
		(fp_line
			(start -0.12065 0.3048)
			(end -0.67945 0.3048)
			(stroke
				(width 0.1)
				(type default)
			)
			(layer "F.Fab")
		)
		(fp_line
			(start -0.67945 0.3048)
			(end -0.67945 -0.305054)
			(stroke
				(width 0.1)
				(type default)
			)
			(layer "F.Fab")
		)
		(pad "1" smd circle
			(at -0.40005 0 90)
			(size 0 0)
			(layers "F.Cu" "F.Mask" "F.Paste")
			(net "PWRGD_P1V8_PEX_R")
		)
		(pad "2" smd circle
			(at 0.40005 0 90)
			(size 0 0)
			(layers "F.Cu" "F.Mask" "F.Paste")
			(net "PWRGD_P1V8_PEX1_R")
		)
	)
	(footprint ""
		(layer "F.Cu")
		(at 435.093364 -311.325514 -90)
		(property "Reference" "R6721"
			(at 0 0 270)
			(layer "F.SilkS")
			(hide yes)
			(effects
				(font
					(size 1.27 1.27)
				)
			)
		)
		(property "Value" ""
			(at 0 0 270)
			(layer "F.Fab")
			(effects
				(font
					(size 1.27 1.27)
				)
			)
		)
		(duplicate_pad_numbers_are_jumpers no)
		(fp_line
			(start -0.7874 0.4064)
			(end -0.7874 -0.4064)
			(stroke
				(width 0.1524)
				(type default)
			)
			(layer "F.SilkS")
		)
		(fp_line
			(start 0.7874 0.4064)
			(end -0.7874 0.4064)
			(stroke
				(width 0.1524)
				(type default)
			)
			(layer "F.SilkS")
		)
		(fp_line
			(start -0.7874 -0.4064)
			(end 0.7874 -0.4064)
			(stroke
				(width 0.1524)
				(type default)
			)
			(layer "F.SilkS")
		)
		(fp_line
			(start 0.7874 -0.4064)
			(end 0.7874 0.4064)
			(stroke
				(width 0.1524)
				(type default)
			)
			(layer "F.SilkS")
		)
		(fp_line
			(start -0.67945 0.3048)
			(end -0.67945 -0.305054)
			(stroke
				(width 0.1)
				(type default)
			)
			(layer "F.Fab")
		)
		(fp_line
			(start -0.12065 0.3048)
			(end -0.67945 0.3048)
			(stroke
				(width 0.1)
				(type default)
			)
			(layer "F.Fab")
		)
		(fp_line
			(start 0.120396 0.3048)
			(end 0.120396 0.2794)
			(stroke
				(width 0.1)
				(type default)
			)
			(layer "F.Fab")
		)
		(fp_line
			(start 0.67945 0.3048)
			(end 0.120396 0.3048)
			(stroke
				(width 0.1)
				(type default)
			)
			(layer "F.Fab")
		)
		(fp_line
			(start -0.12065 0.2794)
			(end -0.12065 0.3048)
			(stroke
				(width 0.1)
				(type default)
			)
			(layer "F.Fab")
		)
		(fp_line
			(start 0.120396 0.2794)
			(end -0.12065 0.2794)
			(stroke
				(width 0.1)
				(type default)
			)
			(layer "F.Fab")
		)
		(fp_line
			(start -0.12065 -0.2794)
			(end 0.12065 -0.2794)
			(stroke
				(width 0.1)
				(type default)
			)
			(layer "F.Fab")
		)
		(fp_line
			(start 0.12065 -0.2794)
			(end 0.12065 -0.3048)
			(stroke
				(width 0.1)
				(type default)
			)
			(layer "F.Fab")
		)
		(fp_line
			(start 0.12065 -0.3048)
			(end 0.67945 -0.3048)
			(stroke
				(width 0.1)
				(type default)
			)
			(layer "F.Fab")
		)
		(fp_line
			(start 0.67945 -0.3048)
			(end 0.67945 0.3048)
			(stroke
				(width 0.1)
				(type default)
			)
			(layer "F.Fab")
		)
		(fp_line
			(start -0.67945 -0.305054)
			(end -0.12065 -0.305054)
			(stroke
				(width 0.1)
				(type default)
			)
			(layer "F.Fab")
		)
		(fp_line
			(start -0.12065 -0.305054)
			(end -0.12065 -0.2794)
			(stroke
				(width 0.1)
				(type default)
			)
			(layer "F.Fab")
		)
		(pad "1" smd circle
			(at -0.40005 0 270)
			(size 0 0)
			(layers "F.Cu" "F.Mask" "F.Paste")
			(net "SMB_PEX3_SLAVE1_SDA")
		)
		(pad "2" smd circle
			(at 0.40005 0 270)
			(size 0 0)
			(layers "F.Cu" "F.Mask" "F.Paste")
			(net "SMB_PEX3_R_SDA")
		)
	)
	(footprint ""
		(layer "F.Cu")
		(at 13.194284 -255.046734 -90)
		(property "Reference" "R6474"
			(at 0 0 270)
			(layer "F.SilkS")
			(hide yes)
			(effects
				(font
					(size 1.27 1.27)
				)
			)
		)
		(property "Value" ""
			(at 0 0 270)
			(layer "F.Fab")
			(effects
				(font
					(size 1.27 1.27)
				)
			)
		)
		(duplicate_pad_numbers_are_jumpers no)
		(fp_line
			(start -0.7874 0.4064)
			(end -0.7874 -0.4064)
			(stroke
				(width 0.1524)
				(type default)
			)
			(layer "F.SilkS")
		)
		(fp_line
			(start 0.7874 0.4064)
			(end -0.7874 0.4064)
			(stroke
				(width 0.1524)
				(type default)
			)
			(layer "F.SilkS")
		)
		(fp_line
			(start -0.7874 -0.4064)
			(end 0.7874 -0.4064)
			(stroke
				(width 0.1524)
				(type default)
			)
			(layer "F.SilkS")
		)
		(fp_line
			(start 0.7874 -0.4064)
			(end 0.7874 0.4064)
			(stroke
				(width 0.1524)
				(type default)
			)
			(layer "F.SilkS")
		)
		(fp_line
			(start -0.67945 0.3048)
			(end -0.67945 -0.305054)
			(stroke
				(width 0.1)
				(type default)
			)
			(layer "F.Fab")
		)
		(fp_line
			(start -0.12065 0.3048)
			(end -0.67945 0.3048)
			(stroke
				(width 0.1)
				(type default)
			)
			(layer "F.Fab")
		)
		(fp_line
			(start 0.120396 0.3048)
			(end 0.120396 0.2794)
			(stroke
				(width 0.1)
				(type default)
			)
			(layer "F.Fab")
		)
		(fp_line
			(start 0.67945 0.3048)
			(end 0.120396 0.3048)
			(stroke
				(width 0.1)
				(type default)
			)
			(layer "F.Fab")
		)
		(fp_line
			(start -0.12065 0.2794)
			(end -0.12065 0.3048)
			(stroke
				(width 0.1)
				(type default)
			)
			(layer "F.Fab")
		)
		(fp_line
			(start 0.120396 0.2794)
			(end -0.12065 0.2794)
			(stroke
				(width 0.1)
				(type default)
			)
			(layer "F.Fab")
		)
		(fp_line
			(start -0.12065 -0.2794)
			(end 0.12065 -0.2794)
			(stroke
				(width 0.1)
				(type default)
			)
			(layer "F.Fab")
		)
		(fp_line
			(start 0.12065 -0.2794)
			(end 0.12065 -0.3048)
			(stroke
				(width 0.1)
				(type default)
			)
			(layer "F.Fab")
		)
		(fp_line
			(start 0.12065 -0.3048)
			(end 0.67945 -0.3048)
			(stroke
				(width 0.1)
				(type default)
			)
			(layer "F.Fab")
		)
		(fp_line
			(start 0.67945 -0.3048)
			(end 0.67945 0.3048)
			(stroke
				(width 0.1)
				(type default)
			)
			(layer "F.Fab")
		)
		(fp_line
			(start -0.67945 -0.305054)
			(end -0.12065 -0.305054)
			(stroke
				(width 0.1)
				(type default)
			)
			(layer "F.Fab")
		)
		(fp_line
			(start -0.12065 -0.305054)
			(end -0.12065 -0.2794)
			(stroke
				(width 0.1)
				(type default)
			)
			(layer "F.Fab")
		)
		(pad "1" smd circle
			(at -0.40005 0 270)
			(size 0 0)
			(layers "F.Cu" "F.Mask" "F.Paste")
			(net "P1V25_SERDES_VDDPLL_PEX0")
		)
		(pad "2" smd circle
			(at 0.40005 0 270)
			(size 0 0)
			(layers "F.Cu" "F.Mask" "F.Paste")
			(net "P1V25_SERDES_VDDPLL_PEX0_C11")
		)
	)
	(footprint ""
		(layer "F.Cu")
		(at 407.190956 -55.663846 90)
		(property "Reference" "PU67"
			(at -0.93726 2.791968 90)
			(unlocked yes)
			(layer "F.SilkS")
			(effects
				(font
					(size 0.7874 0.5842)
					(thickness 0.1524)
				)
				(justify left)
			)
		)
		(property "Value" ""
			(at 0 0 90)
			(layer "F.Fab")
			(effects
				(font
					(size 1.27 1.27)
				)
			)
		)
		(duplicate_pad_numbers_are_jumpers no)
		(fp_line
			(start 1.943608 -1.549908)
			(end 1.943608 1.549908)
			(stroke
				(width 0.1524)
				(type default)
			)
			(layer "F.SilkS")
		)
		(fp_line
			(start -1.943608 -1.549908)
			(end 1.943608 -1.549908)
			(stroke
				(width 0.1524)
				(type default)
			)
			(layer "F.SilkS")
		)
		(fp_line
			(start 1.943608 1.549908)
			(end -1.943608 1.549908)
			(stroke
				(width 0.1524)
				(type default)
			)
			(layer "F.SilkS")
		)
		(fp_line
			(start -1.943608 1.549908)
			(end -1.943608 -1.549908)
			(stroke
				(width 0.1524)
				(type default)
			)
			(layer "F.SilkS")
		)
		(fp_poly
			(pts
				(xy -2.019808 -1.549908) (xy -1.257808 -1.549908) (xy -1.257808 -1.880108) (xy -2.019808 -1.880108)
			)
			(stroke
				(width 0)
				(type default)
			)
			(fill yes)
			(layer "F.SilkS")
		)
		(fp_line
			(start 1.549908 -1.549908)
			(end 1.549908 1.549908)
			(stroke
				(width 0.1)
				(type default)
			)
			(layer "F.Fab")
		)
		(fp_line
			(start -1.549908 -1.549908)
			(end 1.549908 -1.549908)
			(stroke
				(width 0.1)
				(type default)
			)
			(layer "F.Fab")
		)
		(fp_line
			(start 1.549908 1.549908)
			(end -1.549908 1.549908)
			(stroke
				(width 0.1)
				(type default)
			)
			(layer "F.Fab")
		)
		(fp_line
			(start -1.549908 1.549908)
			(end -1.549908 -1.549908)
			(stroke
				(width 0.1)
				(type default)
			)
			(layer "F.Fab")
		)
		(fp_poly
			(pts
				(xy -2.019808 -1.549908) (xy -1.257808 -1.549908) (xy -1.257808 -1.880108) (xy -2.019808 -1.880108)
			)
			(stroke
				(width 0)
				(type default)
			)
			(fill yes)
			(layer "F.Fab")
		)
		(pad "1" smd rect
			(at -1.500124 -1.249934)
			(size 0.2794 0.6096)
			(layers "F.Cu" "F.Mask" "F.Paste")
			(net "P3V3_SSD14")
		)
		(pad "2" smd rect
			(at -1.500124 -0.750062)
			(size 0.2794 0.6096)
			(layers "F.Cu" "F.Mask" "F.Paste")
			(net "P3V3_SSD14")
		)
		(pad "3" smd rect
			(at -1.500124 -0.249936)
			(size 0.2794 0.6096)
			(layers "F.Cu" "F.Mask" "F.Paste")
			(net "P3V3_SSD14")
		)
		(pad "4" smd rect
			(at -1.500124 0.249936)
			(size 0.2794 0.6096)
			(layers "F.Cu" "F.Mask" "F.Paste")
			(net "P3V3_SSD14")
		)
		(pad "5" smd rect
			(at -1.500124 0.750062)
			(size 0.2794 0.6096)
			(layers "F.Cu" "F.Mask" "F.Paste")
			(net "P3V3_SSD14")
		)
		(pad "6" smd rect
			(at -1.500124 1.249934)
			(size 0.2794 0.6096)
			(layers "F.Cu" "F.Mask" "F.Paste")
			(net "GND")
		)
		(pad "7" smd rect
			(at 1.500124 1.249934)
			(size 0.2794 0.6096)
			(layers "F.Cu" "F.Mask" "F.Paste")
			(net "P3V3_SSD14_SS")
		)
		(pad "8" smd rect
			(at 1.500124 0.750062)
			(size 0.2794 0.6096)
			(layers "F.Cu" "F.Mask" "F.Paste")
			(net "PWRGD_P3V3_SSD14")
		)
		(pad "9" smd rect
			(at 1.500124 0.249936)
			(size 0.2794 0.6096)
			(layers "F.Cu" "F.Mask" "F.Paste")
			(net "P3V3_SSD14_OCP")
		)
		(pad "10" smd rect
			(at 1.500124 -0.249936)
			(size 0.2794 0.6096)
			(layers "F.Cu" "F.Mask" "F.Paste")
			(net "P5V_AUX")
		)
		(pad "11" smd rect
			(at 1.500124 -0.750062)
			(size 0.2794 0.6096)
			(layers "F.Cu" "F.Mask" "F.Paste")
			(net "SSD14_AUX_P3V3_EN_R")
		)
		(pad "12" smd rect
			(at 1.500124 -1.249934)
			(size 0.2794 0.6096)
			(layers "F.Cu" "F.Mask" "F.Paste")
			(net "P3V3_AUX")
		)
		(pad "13" smd rect
			(at 0 0 90)
			(size 1.9812 2.7178)
			(layers "F.Cu" "F.Mask" "F.Paste")
			(net "P3V3_AUX")
		)
		(zone
			(layer "F.Cu")
			(hatch none 0.5)
			(connect_pads
				(clearance 0)
			)
			(min_thickness 0.25)
			(keepout
				(tracks not_allowed)
				(vias allowed)
				(pads allowed)
				(copperpour not_allowed)
				(footprints allowed)
			)
			(placement
				(enabled no)
				(sheetname "")
			)
			(fill
				(thermal_gap 0.5)
				(thermal_bridge_width 0.5)
				(island_removal_mode 0)
			)
			(polygon
				(pts
					(xy 405.641556 -56.806846) (xy 405.768556 -56.806846) (xy 408.740356 -56.806846) (xy 408.740864 -56.806846)
					(xy 408.740864 -54.520846) (xy 408.740356 -54.520846) (xy 408.613356 -54.520846) (xy 407.190956 -54.520846)
					(xy 407.190956 -54.622446) (xy 408.613356 -54.622446) (xy 408.613356 -56.705246) (xy 405.768556 -56.705246)
					(xy 405.768556 -54.622446) (xy 407.165556 -54.622446) (xy 407.165556 -54.520846) (xy 405.768556 -54.520846)
					(xy 405.641556 -54.520846) (xy 405.641048 -54.520846) (xy 405.641048 -56.806846)
				)
			)
		)
	)
)
